# TIMECARD (Time Appliance Project (Time Card)) — schematic netlist excerpt (pin names and nets, part order shuffled) for the footprints in the layout excerpt that follows; sources: Cadence DE-HDL packaged netlist, KiCad conversion of R4006-B0001-02_R01.brd

TP45  TP_PIONT  pkg TP010CT020B030_PTH  page 25 : \1\ = FPGA_PROGRAM_N
L7  FERRITEBEAD  26OHM 25%  pkg SMC_0603R_H030  page 32 : \1\ = XP12R0V ; \2\ = VIN_XP5R0V

(kicad_pcb
	(version 20260206)
	(generator "pcbnew")
	(generator_version "10.0")
	(general
		(thickness 1.6)
		(legacy_teardrops no)
	)
	(paper "A4")
	(title_block
		(title "timecard-production-celestica-r4006 — R4006-B0001-02_R01.brd")
		(comment 1 "Time Appliance Project (Time Card) / footprints 61-62 of 1113")
	)
	(layers
		(0 "F.Cu" signal "TOP")
		(4 "In1.Cu" signal "L02_GND1")
		(6 "In2.Cu" signal "L03_SIG1")
		(8 "In3.Cu" signal "L04_GND2")
		(10 "In4.Cu" signal "L05_VCC1")
		(12 "In5.Cu" signal "L06_VCC2")
		(14 "In6.Cu" signal "L07_GND3")
		(16 "In7.Cu" signal "L08_SIG2")
		(18 "In8.Cu" signal "L09_GND4")
		(2 "B.Cu" signal "BOTTOM")
		(9 "F.Adhes" user "F.Adhesive")
		(11 "B.Adhes" user "B.Adhesive")
		(13 "F.Paste" user "Package Geometry/Pastemask Top")
		(15 "B.Paste" user "Package Geometry/Pastemask Bottom")
		(5 "F.SilkS" user "Ref Des/Silkscreen Top")
		(7 "B.SilkS" user "Ref Des/Silkscreen Bottom")
		(1 "F.Mask" user "Board Geometry/Soldermask Top")
		(3 "B.Mask" user "Board Geometry/Soldermask Bottom")
		(17 "Dwgs.User" user "User.Drawings")
		(19 "Cmts.User" user "User.Comments")
		(21 "Eco1.User" user "User.Eco1")
		(23 "Eco2.User" user "User.Eco2")
		(25 "Edge.Cuts" user "Board Geometry/Outline")
		(27 "Margin" user)
		(31 "F.CrtYd" user "Package Geometry/Place Bound Top")
		(29 "B.CrtYd" user "Package Geometry/Place Bound Bottom")
		(35 "F.Fab" user "Ref Des/Assembly Top")
		(33 "B.Fab" user "Ref Des/Assembly Bottom")
	)
	(footprint ""
		(layer "F.Cu")
		(at 39.6494 -95.9104)
		(property "Reference" "L7"
			(at -0.2032 1.46177 0)
			(unlocked yes)
			(layer "F.SilkS")
			(effects
				(font
					(size 0.7874 0.5842)
					(thickness 0.1524)
				)
				(justify left)
			)
		)
		(property "Value" "VAL*"
			(at -0.9398 3.70967 0)
			(unlocked yes)
			(layer "F.Fab")
			(hide yes)
			(effects
				(font
					(size 0.7874 0.5842)
					(thickness 0.1524)
				)
				(justify left)
			)
		)
		(property "Tolerance" "TOL*"
			(at -0.9906 5.00507 0)
			(unlocked yes)
			(layer "Cmts.User")
			(hide yes)
			(effects
				(font
					(size 0.7874 0.5842)
					(thickness 0.1524)
				)
				(justify left)
			)
		)
		(property "User Part Number" "PARTNUM*"
			(at -2.54 2.46507 0)
			(unlocked yes)
			(layer "Cmts.User")
			(hide yes)
			(effects
				(font
					(size 0.7874 0.5842)
					(thickness 0.1524)
				)
				(justify left)
			)
		)
		(property "Device Type" "FERRITEBEAD-G191-10101-01,26OHA"
			(at -0.9906 1.22047 0)
			(unlocked yes)
			(layer "F.Fab")
			(hide yes)
			(effects
				(font
					(size 0.7874 0.5842)
					(thickness 0.1524)
				)
				(justify left)
			)
		)
		(duplicate_pad_numbers_are_jumpers no)
		(fp_line
			(start -1.3208 -0.7112)
			(end 1.3208 -0.7112)
			(stroke
				(width 0.1)
				(type default)
			)
			(layer "F.SilkS")
		)
		(fp_line
			(start -1.3208 0.7112)
			(end -1.3208 -0.7112)
			(stroke
				(width 0.1)
				(type default)
			)
			(layer "F.SilkS")
		)
		(fp_line
			(start 1.3208 -0.7112)
			(end 1.3208 0.7112)
			(stroke
				(width 0.1)
				(type default)
			)
			(layer "F.SilkS")
		)
		(fp_line
			(start 1.3208 0.7112)
			(end -1.3208 0.7112)
			(stroke
				(width 0.1)
				(type default)
			)
			(layer "F.SilkS")
		)
		(fp_rect
			(start -1.3208 0.7112)
			(end 1.3208 -0.7112)
			(stroke
				(width 0)
				(type default)
			)
			(fill no)
			(layer "F.CrtYd")
		)
		(fp_line
			(start -0.8128 -0.4572)
			(end 0.8128 -0.4572)
			(stroke
				(width 0.1)
				(type default)
			)
			(layer "F.Fab")
		)
		(fp_line
			(start -0.8128 0.4572)
			(end -0.8128 -0.4572)
			(stroke
				(width 0.1)
				(type default)
			)
			(layer "F.Fab")
		)
		(fp_line
			(start 0.8128 -0.4572)
			(end 0.8128 0.4572)
			(stroke
				(width 0.1)
				(type default)
			)
			(layer "F.Fab")
		)
		(fp_line
			(start 0.8128 0.4572)
			(end -0.8128 0.4572)
			(stroke
				(width 0.1)
				(type default)
			)
			(layer "F.Fab")
		)
		(pad "1" smd rect
			(at -0.6858 0)
			(size 0.762 0.8636)
			(layers "F.Cu" "F.Mask" "F.Paste")
			(net "XP12R0V")
		)
		(pad "2" smd rect
			(at 0.6858 0)
			(size 0.762 0.8636)
			(layers "F.Cu" "F.Mask" "F.Paste")
			(net "VIN_XP5R0V")
		)
		(zone
			(layer "F.Cu")
			(hatch none 0.5)
			(connect_pads
				(clearance 0)
			)
			(min_thickness 0.25)
			(keepout
				(tracks allowed)
				(vias not_allowed)
				(pads allowed)
				(copperpour not_allowed)
				(footprints allowed)
			)
			(placement
				(enabled no)
				(sheetname "")
			)
			(fill
				(thermal_gap 0.5)
				(thermal_bridge_width 0.5)
				(island_removal_mode 0)
			)
			(polygon
				(pts
					(xy 39.497 -95.4532) (xy 39.8018 -95.4532) (xy 39.8018 -96.3676) (xy 39.497 -96.3676)
				)
			)
		)
		(zone
			(layer "F.Cu")
			(hatch none 0.5)
			(connect_pads
				(clearance 0)
			)
			(min_thickness 0.25)
			(keepout
				(tracks not_allowed)
				(vias allowed)
				(pads allowed)
				(copperpour not_allowed)
				(footprints allowed)
			)
			(placement
				(enabled no)
				(sheetname "")
			)
			(fill
				(thermal_gap 0.5)
				(thermal_bridge_width 0.5)
				(island_removal_mode 0)
			)
			(polygon
				(pts
					(xy 39.497 -95.4532) (xy 39.8018 -95.4532) (xy 39.8018 -96.3676) (xy 39.497 -96.3676)
				)
			)
		)
	)
	(footprint ""
		(layer "F.Cu")
		(at 122.428 -53.975)
		(property "Reference" "TP45"
			(at -0.08763 -0.8128 90)
			(unlocked yes)
			(layer "F.SilkS")
			(effects
				(font
					(size 0.7874 0.5842)
					(thickness 0.1524)
				)
				(justify left)
			)
		)
		(property "Value" ""
			(at 0 0 0)
			(layer "F.Fab")
			(effects
				(font
					(size 1.27 1.27)
				)
			)
		)
		(property "Device Type" "TP_PIONT-TP010CT020B030_PTH-TPA"
			(at -1.341882 0.996696 0)
			(unlocked yes)
			(layer "F.Fab")
			(hide yes)
			(effects
				(font
					(size 0.7874 0.5842)
					(thickness 0.000001)
				)
				(justify left)
			)
		)
		(duplicate_pad_numbers_are_jumpers no)
		(fp_poly
			(pts
				(arc
					(start 0.889 0)
					(mid -0.889 0)
					(end 0.889 0)
				)
			)
			(stroke
				(width 0)
				(type default)
			)
			(fill no)
			(layer "B.CrtYd")
		)
		(fp_poly
			(pts
				(arc
					(start 0.889 0)
					(mid -0.889 0)
					(end 0.889 0)
				)
			)
			(stroke
				(width 0)
				(type default)
			)
			(fill no)
			(layer "F.CrtYd")
		)
		(pad "1" thru_hole circle
			(at 0 0)
			(size 0.508 0.508)
			(drill 0.254)
			(layers "*.Cu" "*.Mask")
			(remove_unused_layers no)
			(net "FPGA_PROGRAM_N")
			(clearance 0.1016)
			(padstack
				(mode front_inner_back)
				(layer "Inner"
					(shape circle)
					(size 0.508 0.508)
					(clearance 0.1016)
				)
				(layer "B.Cu"
					(shape circle)
					(size 0.762 0.762)
					(clearance -0.0254)
				)
			)
		)
	)
)
